# S9S_MB_2U (Grand Teton) — schematic netlist excerpt (pin names and nets, part order shuffled) for the footprints in the layout excerpt that follows; sources: Cadence DE-HDL packaged netlist, KiCad conversion of 03242023_DA0F0TMBIJ0_F0T_Motherboard_J_brd_V01_OCP.brd

U104  74LVC1G07GV  IC  pkg SC-74A_2-9X1-5  page 155
  NC1  = NC_U104_NC1
  A  = FM_SYS_THROTTLE_R_N
  GND  = GND
  Y  = OCP_SFF_PWRBRK_BUFF_N
  VCC  = P3V3_AUX

(kicad_pcb
	(version 20260206)
	(generator "pcbnew")
	(generator_version "10.0")
	(general
		(thickness 1.6)
		(legacy_teardrops no)
	)
	(paper "A4")
	(title_block
		(title "03242023_DA0F0TMBIJ0_F0T_Motherboard_J_brd_V01_OCP.brd")
		(comment 1 "Grand Teton / footprints 1367-1367 of 6105")
	)
	(layers
		(0 "F.Cu" signal "TOP")
		(4 "In1.Cu" signal "GND")
		(6 "In2.Cu" signal "IN1")
		(8 "In3.Cu" signal "GND1")
		(10 "In4.Cu" signal "IN2")
		(12 "In5.Cu" signal "GND2")
		(14 "In6.Cu" signal "IN3")
		(16 "In7.Cu" signal "GND3")
		(18 "In8.Cu" signal "VCC")
		(20 "In9.Cu" signal "VCC1")
		(22 "In10.Cu" signal "GND4")
		(24 "In11.Cu" signal "IN4")
		(26 "In12.Cu" signal "GND5")
		(28 "In13.Cu" signal "IN5")
		(30 "In14.Cu" signal "GND6")
		(32 "In15.Cu" signal "IN6")
		(34 "In16.Cu" signal "GND7")
		(2 "B.Cu" signal "BOTTOM")
		(9 "F.Adhes" user "F.Adhesive")
		(11 "B.Adhes" user "B.Adhesive")
		(13 "F.Paste" user "Package Geometry/Pastemask Top")
		(15 "B.Paste" user "Package Geometry/Pastemask Bottom")
		(5 "F.SilkS" user "Ref Des/Silkscreen Top")
		(7 "B.SilkS" user "Ref Des/Silkscreen Bottom")
		(1 "F.Mask" user "Board Geometry/Soldermask Top")
		(3 "B.Mask" user "Board Geometry/Soldermask Bottom")
		(17 "Dwgs.User" user "User.Drawings")
		(19 "Cmts.User" user "User.Comments")
		(21 "Eco1.User" user "User.Eco1")
		(23 "Eco2.User" user "User.Eco2")
		(25 "Edge.Cuts" user "Board Geometry/Outline")
		(27 "Margin" user)
		(31 "F.CrtYd" user "Package Geometry/Place Bound Top")
		(29 "B.CrtYd" user "Package Geometry/Place Bound Bottom")
		(35 "F.Fab" user "Ref Des/Assembly Top")
		(33 "B.Fab" user "Ref Des/Assembly Bottom")
	)
	(footprint ""
		(layer "F.Cu")
		(at 390.056878 -28.309824 90)
		(property "Reference" "U104"
			(at -0.177546 2.754122 0)
			(unlocked yes)
			(layer "F.SilkS")
			(effects
				(font
					(size 0.7874 0.5842)
					(thickness 0.1524)
				)
				(justify left)
			)
		)
		(property "Value" ""
			(at 0 0 90)
			(layer "F.Fab")
			(effects
				(font
					(size 1.27 1.27)
				)
			)
		)
		(duplicate_pad_numbers_are_jumpers no)
		(fp_line
			(start 1.733296 -1.549908)
			(end 0.660908 -1.549908)
			(stroke
				(width 0.1524)
				(type default)
			)
			(layer "F.SilkS")
		)
		(fp_line
			(start 0.660908 -1.549908)
			(end 0 -0.889)
			(stroke
				(width 0.1524)
				(type default)
			)
			(layer "F.SilkS")
		)
		(fp_line
			(start -0.660908 -1.549908)
			(end -1.733296 -1.549908)
			(stroke
				(width 0.1524)
				(type default)
			)
			(layer "F.SilkS")
		)
		(fp_line
			(start -1.733296 -1.549908)
			(end -1.733296 1.549908)
			(stroke
				(width 0.1524)
				(type default)
			)
			(layer "F.SilkS")
		)
		(fp_line
			(start 0 -0.889)
			(end -0.660908 -1.549908)
			(stroke
				(width 0.1524)
				(type default)
			)
			(layer "F.SilkS")
		)
		(fp_line
			(start 1.733296 1.549908)
			(end 1.733296 -1.549908)
			(stroke
				(width 0.1524)
				(type default)
			)
			(layer "F.SilkS")
		)
		(fp_line
			(start -1.733296 1.549908)
			(end 1.733296 1.549908)
			(stroke
				(width 0.1524)
				(type default)
			)
			(layer "F.SilkS")
		)
		(fp_poly
			(pts
				(xy -1.227836 -2.218436) (xy -1.481836 -1.710436) (xy -1.735836 -2.218436)
			)
			(stroke
				(width 0)
				(type default)
			)
			(fill yes)
			(layer "F.SilkS")
		)
		(fp_line
			(start 0.849884 -1.549908)
			(end -0.849884 -1.549908)
			(stroke
				(width 0.1)
				(type default)
			)
			(layer "F.Fab")
		)
		(fp_line
			(start -0.849884 -1.549908)
			(end -0.849884 1.549908)
			(stroke
				(width 0.1)
				(type default)
			)
			(layer "F.Fab")
		)
		(fp_line
			(start 0.849884 1.549908)
			(end 0.849884 -1.549908)
			(stroke
				(width 0.1)
				(type default)
			)
			(layer "F.Fab")
		)
		(fp_line
			(start -0.849884 1.549908)
			(end 0.849884 1.549908)
			(stroke
				(width 0.1)
				(type default)
			)
			(layer "F.Fab")
		)
		(fp_poly
			(pts
				(xy -2.4384 -1.20396) (xy -2.4384 -0.69596) (xy -1.9304 -0.94996)
			)
			(stroke
				(width 0)
				(type default)
			)
			(fill yes)
			(layer "F.Fab")
		)
		(pad "1" smd rect
			(at -1.199896 -0.94996)
			(size 0.5588 0.8128)
			(layers "F.Cu" "F.Mask" "F.Paste")
			(net "NC_U104_NC1")
		)
		(pad "2" smd rect
			(at -1.199896 0)
			(size 0.5588 0.8128)
			(layers "F.Cu" "F.Mask" "F.Paste")
			(net "FM_SYS_THROTTLE_R_N")
		)
		(pad "3" smd rect
			(at -1.199896 0.94996)
			(size 0.5588 0.8128)
			(layers "F.Cu" "F.Mask" "F.Paste")
			(net "GND")
		)
		(pad "4" smd rect
			(at 1.199896 0.94996)
			(size 0.5588 0.8128)
			(layers "F.Cu" "F.Mask" "F.Paste")
			(net "OCP_SFF_PWRBRK_BUFF_N")
		)
		(pad "5" smd rect
			(at 1.199896 -0.94996)
			(size 0.5588 0.8128)
			(layers "F.Cu" "F.Mask" "F.Paste")
			(net "P3V3_AUX")
		)
	)
)
